(kicad_pcb
	(version 20260206)
	(generator "pcbnew")
	(generator_version "10.0")
	(general
		(thickness 1.6)
		(legacy_teardrops no)
	)
	(paper "A4")
	(title_block
		(title "Bryce Canyon_IOM_M2_16342-2_OCP.brd")
		(comment 1 "Bryce Canyon / footprint 242 of 1146 (MEZZ1), pads 118-122 of 122")
	)
	(layers
		(0 "F.Cu" signal "TOP")
		(4 "In1.Cu" signal "L2GND")
		(6 "In2.Cu" signal "L3")
		(8 "In3.Cu" signal "L4VCC")
		(10 "In4.Cu" signal "L5VCC")
		(12 "In5.Cu" signal "L6")
		(14 "In6.Cu" signal "L7GND")
		(2 "B.Cu" signal "BOTTOM")
		(9 "F.Adhes" user "F.Adhesive")
		(11 "B.Adhes" user "B.Adhesive")
		(13 "F.Paste" user "Package Geometry/Pastemask Top")
		(15 "B.Paste" user "Package Geometry/Pastemask Bottom")
		(5 "F.SilkS" user "Ref Des/Silkscreen Top")
		(7 "B.SilkS" user "Ref Des/Silkscreen Bottom")
		(1 "F.Mask" user "Board Geometry/Soldermask Top")
		(3 "B.Mask" user "Board Geometry/Soldermask Bottom")
		(17 "Dwgs.User" user "User.Drawings")
		(19 "Cmts.User" user "User.Comments")
		(21 "Eco1.User" user "User.Eco1")
		(23 "Eco2.User" user "User.Eco2")
		(25 "Edge.Cuts" user "Board Geometry/Outline")
		(27 "Margin" user)
		(31 "F.CrtYd" user "Package Geometry/Place Bound Top")
		(29 "B.CrtYd" user "Package Geometry/Place Bound Bottom")
		(35 "F.Fab" user "Ref Des/Assembly Top")
		(33 "B.Fab" user "Ref Des/Assembly Bottom")
	)
	(footprint ""
		(layer "F.Cu")
		(at 77.700124 -72.55002 -90)
		(property "Reference" "MEZZ1"
			(at 0 0 270)
			(layer "F.SilkS")
			(hide yes)
			(effects
				(font
					(size 1.27 1.27)
				)
			)
		)
		(property "Value" "FCI-CONN120-GP-U1"
			(at -28.2321 -1.7018 270)
			(unlocked yes)
			(layer "F.Fab")
			(hide yes)
			(effects
				(font
					(size 1.016 1.016)
					(thickness 0.1524)
				)
			)
		)
		(property "Device Type" "61082-121402LF-U1"
			(at -28.2321 -3.2258 270)
			(unlocked yes)
			(layer "F.Fab")
			(hide yes)
			(effects
				(font
					(size 1.016 1.016)
					(thickness 0.1524)
				)
			)
		)
		(duplicate_pad_numbers_are_jumpers no)
		(pad "116" smd rect
			(at -20.40001 2.22504 270)
			(size 0.508 2.0574)
			(layers "F.Cu" "F.Mask" "F.Paste")
			(net "PCIE_COMP_TO_IOM_23_DP")
		)
		(pad "117" smd rect
			(at -21.20011 2.22504 270)
			(size 0.508 2.0574)
			(layers "F.Cu" "F.Mask" "F.Paste")
			(net "PCIE_COMP_TO_IOM_23_DN")
		)
		(pad "118" smd rect
			(at -21.999956 2.22504 270)
			(size 0.508 2.0574)
			(layers "F.Cu" "F.Mask" "F.Paste")
			(net "GND")
		)
		(pad "119" smd rect
			(at -22.800056 2.22504 270)
			(size 0.508 2.0574)
			(layers "F.Cu" "F.Mask" "F.Paste")
			(net "GND")
		)
		(pad "120" smd rect
			(at -23.599902 2.22504 270)
			(size 0.508 2.0574)
			(layers "F.Cu" "F.Mask" "F.Paste")
			(net "MEZZ_A_PRSNT_120_N")
		)
	)
)
